(kicad_pcb
	(version 20260206)
	(generator "pcbnew")
	(generator_version "10.0")
	(general
		(thickness 1.6)
		(legacy_teardrops no)
	)
	(paper "A4")
	(title_block
		(title "04192023_DAF0TMB3IC0_F0TG_MB_C_brd_V02_OCP.brd")
		(comment 1 "Grand Teton / footprints 165-172 of 8354")
	)
	(layers
		(0 "F.Cu" signal "TOP")
		(4 "In1.Cu" signal "GND")
		(6 "In2.Cu" signal "IN1")
		(8 "In3.Cu" signal "GND1")
		(10 "In4.Cu" signal "IN2")
		(12 "In5.Cu" signal "GND2")
		(14 "In6.Cu" signal "IN3")
		(16 "In7.Cu" signal "GND3")
		(18 "In8.Cu" signal "VCC")
		(20 "In9.Cu" signal "VCC1")
		(22 "In10.Cu" signal "GND4")
		(24 "In11.Cu" signal "IN4")
		(26 "In12.Cu" signal "GND5")
		(28 "In13.Cu" signal "IN5")
		(30 "In14.Cu" signal "GND6")
		(32 "In15.Cu" signal "IN6")
		(34 "In16.Cu" signal "GND7")
		(2 "B.Cu" signal "BOTTOM")
		(9 "F.Adhes" user "F.Adhesive")
		(11 "B.Adhes" user "B.Adhesive")
		(13 "F.Paste" user "Package Geometry/Pastemask Top")
		(15 "B.Paste" user "Package Geometry/Pastemask Bottom")
		(5 "F.SilkS" user "Ref Des/Silkscreen Top")
		(7 "B.SilkS" user "Ref Des/Silkscreen Bottom")
		(1 "F.Mask" user "Board Geometry/Soldermask Top")
		(3 "B.Mask" user "Board Geometry/Soldermask Bottom")
		(17 "Dwgs.User" user "User.Drawings")
		(19 "Cmts.User" user "User.Comments")
		(21 "Eco1.User" user "User.Eco1")
		(23 "Eco2.User" user "User.Eco2")
		(25 "Edge.Cuts" user "Board Geometry/Outline")
		(27 "Margin" user)
		(31 "F.CrtYd" user "Package Geometry/Place Bound Top")
		(29 "B.CrtYd" user "Package Geometry/Place Bound Bottom")
		(35 "F.Fab" user "Ref Des/Assembly Top")
		(33 "B.Fab" user "Ref Des/Assembly Bottom")
	)
	(footprint ""
		(layer "F.Cu")
		(at 279.022556 -438.001664 -90)
		(property "Reference" "R4551"
			(at 0 0 270)
			(layer "F.SilkS")
			(hide yes)
			(effects
				(font
					(size 1.27 1.27)
				)
			)
		)
		(property "Value" ""
			(at 0 0 270)
			(layer "F.Fab")
			(effects
				(font
					(size 1.27 1.27)
				)
			)
		)
		(duplicate_pad_numbers_are_jumpers no)
		(fp_line
			(start -0.7874 0.4064)
			(end -0.7874 -0.4064)
			(stroke
				(width 0.1524)
				(type default)
			)
			(layer "F.SilkS")
		)
		(fp_line
			(start 0.7874 0.4064)
			(end -0.7874 0.4064)
			(stroke
				(width 0.1524)
				(type default)
			)
			(layer "F.SilkS")
		)
		(fp_line
			(start -0.7874 -0.4064)
			(end 0.7874 -0.4064)
			(stroke
				(width 0.1524)
				(type default)
			)
			(layer "F.SilkS")
		)
		(fp_line
			(start 0.7874 -0.4064)
			(end 0.7874 0.4064)
			(stroke
				(width 0.1524)
				(type default)
			)
			(layer "F.SilkS")
		)
		(fp_line
			(start -0.67945 0.3048)
			(end -0.67945 -0.305054)
			(stroke
				(width 0.1)
				(type default)
			)
			(layer "F.Fab")
		)
		(fp_line
			(start -0.12065 0.3048)
			(end -0.67945 0.3048)
			(stroke
				(width 0.1)
				(type default)
			)
			(layer "F.Fab")
		)
		(fp_line
			(start 0.120396 0.3048)
			(end 0.120396 0.2794)
			(stroke
				(width 0.1)
				(type default)
			)
			(layer "F.Fab")
		)
		(fp_line
			(start 0.67945 0.3048)
			(end 0.120396 0.3048)
			(stroke
				(width 0.1)
				(type default)
			)
			(layer "F.Fab")
		)
		(fp_line
			(start -0.12065 0.2794)
			(end -0.12065 0.3048)
			(stroke
				(width 0.1)
				(type default)
			)
			(layer "F.Fab")
		)
		(fp_line
			(start 0.120396 0.2794)
			(end -0.12065 0.2794)
			(stroke
				(width 0.1)
				(type default)
			)
			(layer "F.Fab")
		)
		(fp_line
			(start -0.12065 -0.2794)
			(end 0.12065 -0.2794)
			(stroke
				(width 0.1)
				(type default)
			)
			(layer "F.Fab")
		)
		(fp_line
			(start 0.12065 -0.2794)
			(end 0.12065 -0.3048)
			(stroke
				(width 0.1)
				(type default)
			)
			(layer "F.Fab")
		)
		(fp_line
			(start 0.12065 -0.3048)
			(end 0.67945 -0.3048)
			(stroke
				(width 0.1)
				(type default)
			)
			(layer "F.Fab")
		)
		(fp_line
			(start 0.67945 -0.3048)
			(end 0.67945 0.3048)
			(stroke
				(width 0.1)
				(type default)
			)
			(layer "F.Fab")
		)
		(fp_line
			(start -0.67945 -0.305054)
			(end -0.12065 -0.305054)
			(stroke
				(width 0.1)
				(type default)
			)
			(layer "F.Fab")
		)
		(fp_line
			(start -0.12065 -0.305054)
			(end -0.12065 -0.2794)
			(stroke
				(width 0.1)
				(type default)
			)
			(layer "F.Fab")
		)
		(pad "1" smd circle
			(at -0.40005 0 270)
			(size 0 0)
			(layers "F.Cu" "F.Mask" "F.Paste")
			(net "P3V3_AUX")
		)
		(pad "2" smd circle
			(at 0.40005 0 270)
			(size 0 0)
			(layers "F.Cu" "F.Mask" "F.Paste")
			(net "HPDB_HSC_PWRGD")
		)
	)
	(footprint ""
		(layer "F.Cu")
		(at 60.021724 -408.517344 -90)
		(property "Reference" "C6638"
			(at 0 0 270)
			(layer "F.SilkS")
			(hide yes)
			(effects
				(font
					(size 1.27 1.27)
				)
			)
		)
		(property "Value" ""
			(at 0 0 270)
			(layer "F.Fab")
			(effects
				(font
					(size 1.27 1.27)
				)
			)
		)
		(duplicate_pad_numbers_are_jumpers no)
		(fp_line
			(start -0.299974 0.150114)
			(end -0.299974 -0.150114)
			(stroke
				(width 0.1)
				(type default)
			)
			(layer "F.Fab")
		)
		(fp_line
			(start 0.299974 0.150114)
			(end -0.299974 0.150114)
			(stroke
				(width 0.1)
				(type default)
			)
			(layer "F.Fab")
		)
		(fp_line
			(start -0.299974 -0.150114)
			(end 0.299974 -0.150114)
			(stroke
				(width 0.1)
				(type default)
			)
			(layer "F.Fab")
		)
		(fp_line
			(start 0.299974 -0.150114)
			(end 0.299974 0.150114)
			(stroke
				(width 0.1)
				(type default)
			)
			(layer "F.Fab")
		)
		(pad "1" smd rect
			(at -0.2667 0 270)
			(size 0.3048 0.381)
			(layers "F.Cu" "F.Mask" "F.Paste")
			(net "P5E_CPU1_P0_TX_BUF_C_DN<4>")
		)
		(pad "2" smd rect
			(at 0.2667 0 270)
			(size 0.3048 0.381)
			(layers "F.Cu" "F.Mask" "F.Paste")
			(net "P5E_CPU1_P0_TX_BUF_DN<4>")
		)
	)
	(footprint ""
		(layer "F.Cu")
		(at 448.799966 -435.59984)
		(property "Reference" "H90"
			(at -2.943352 -3.737864 0)
			(unlocked yes)
			(layer "F.SilkS")
			(effects
				(font
					(size 0.7874 0.5842)
					(thickness 0.1524)
				)
				(justify left)
			)
		)
		(property "Value" ""
			(at 0 0 0)
			(layer "F.Fab")
			(effects
				(font
					(size 1.27 1.27)
				)
			)
		)
		(duplicate_pad_numbers_are_jumpers no)
		(fp_circle
			(center 0 0)
			(end 2.6289 0)
			(stroke
				(width 0.1524)
				(type default)
			)
			(fill no)
			(layer "F.SilkS")
		)
		(fp_circle
			(center 0 0)
			(end 2.6289 0)
			(stroke
				(width 0.1524)
				(type default)
			)
			(fill no)
			(layer "B.SilkS")
		)
		(fp_circle
			(center 0 0)
			(end 2.6289 0)
			(stroke
				(width 0.1)
				(type default)
			)
			(fill no)
			(layer "B.Fab")
		)
		(fp_circle
			(center 0 0)
			(end 2.6289 0)
			(stroke
				(width 0.1)
				(type default)
			)
			(fill no)
			(layer "F.Fab")
		)
		(pad "" np_thru_hole circle
			(at 0 0)
			(size 3.0988 3.0988)
			(drill 3.0988)
			(layers "*.Cu" "*.Mask")
			(clearance 0.254)
			(thermal_gap 0.254)
		)
		(zone
			(layers "F.Cu" "B.Cu" "In1.Cu" "In2.Cu" "In3.Cu" "In4.Cu" "In5.Cu" "In6.Cu"
				"In7.Cu" "In8.Cu" "In9.Cu" "In10.Cu" "In11.Cu" "In12.Cu" "In13.Cu" "In14.Cu"
				"In15.Cu" "In16.Cu"
			)
			(hatch none 0.5)
			(connect_pads
				(clearance 0)
			)
			(min_thickness 0.25)
			(keepout
				(tracks not_allowed)
				(vias allowed)
				(pads allowed)
				(copperpour not_allowed)
				(footprints allowed)
			)
			(placement
				(enabled no)
				(sheetname "")
			)
			(fill
				(thermal_gap 0.5)
				(thermal_bridge_width 0.5)
				(island_removal_mode 0)
			)
			(polygon
				(pts
					(arc
						(start 450.857366 -435.59984)
						(mid 446.742566 -435.59984)
						(end 450.857366 -435.59984)
					)
				)
			)
		)
	)
	(footprint ""
		(layer "F.Cu")
		(at 226.0981 -408.084782)
		(property "Reference" "PR3989"
			(at 0 0 0)
			(layer "F.SilkS")
			(hide yes)
			(effects
				(font
					(size 1.27 1.27)
				)
			)
		)
		(property "Value" ""
			(at 0 0 0)
			(layer "F.Fab")
			(effects
				(font
					(size 1.27 1.27)
				)
			)
		)
		(duplicate_pad_numbers_are_jumpers no)
		(fp_line
			(start -0.7874 -0.4064)
			(end 0.7874 -0.4064)
			(stroke
				(width 0.1524)
				(type default)
			)
			(layer "F.SilkS")
		)
		(fp_line
			(start -0.7874 0.4064)
			(end -0.7874 -0.4064)
			(stroke
				(width 0.1524)
				(type default)
			)
			(layer "F.SilkS")
		)
		(fp_line
			(start 0.7874 -0.4064)
			(end 0.7874 0.4064)
			(stroke
				(width 0.1524)
				(type default)
			)
			(layer "F.SilkS")
		)
		(fp_line
			(start 0.7874 0.4064)
			(end -0.7874 0.4064)
			(stroke
				(width 0.1524)
				(type default)
			)
			(layer "F.SilkS")
		)
		(fp_line
			(start -0.67945 -0.305054)
			(end -0.12065 -0.305054)
			(stroke
				(width 0.1)
				(type default)
			)
			(layer "F.Fab")
		)
		(fp_line
			(start -0.67945 0.3048)
			(end -0.67945 -0.305054)
			(stroke
				(width 0.1)
				(type default)
			)
			(layer "F.Fab")
		)
		(fp_line
			(start -0.12065 -0.305054)
			(end -0.12065 -0.2794)
			(stroke
				(width 0.1)
				(type default)
			)
			(layer "F.Fab")
		)
		(fp_line
			(start -0.12065 -0.2794)
			(end 0.12065 -0.2794)
			(stroke
				(width 0.1)
				(type default)
			)
			(layer "F.Fab")
		)
		(fp_line
			(start -0.12065 0.2794)
			(end -0.12065 0.3048)
			(stroke
				(width 0.1)
				(type default)
			)
			(layer "F.Fab")
		)
		(fp_line
			(start -0.12065 0.3048)
			(end -0.67945 0.3048)
			(stroke
				(width 0.1)
				(type default)
			)
			(layer "F.Fab")
		)
		(fp_line
			(start 0.120396 0.2794)
			(end -0.12065 0.2794)
			(stroke
				(width 0.1)
				(type default)
			)
			(layer "F.Fab")
		)
		(fp_line
			(start 0.120396 0.3048)
			(end 0.120396 0.2794)
			(stroke
				(width 0.1)
				(type default)
			)
			(layer "F.Fab")
		)
		(fp_line
			(start 0.12065 -0.3048)
			(end 0.67945 -0.3048)
			(stroke
				(width 0.1)
				(type default)
			)
			(layer "F.Fab")
		)
		(fp_line
			(start 0.12065 -0.2794)
			(end 0.12065 -0.3048)
			(stroke
				(width 0.1)
				(type default)
			)
			(layer "F.Fab")
		)
		(fp_line
			(start 0.67945 -0.3048)
			(end 0.67945 0.3048)
			(stroke
				(width 0.1)
				(type default)
			)
			(layer "F.Fab")
		)
		(fp_line
			(start 0.67945 0.3048)
			(end 0.120396 0.3048)
			(stroke
				(width 0.1)
				(type default)
			)
			(layer "F.Fab")
		)
		(pad "1" smd circle
			(at -0.40005 0)
			(size 0 0)
			(layers "F.Cu" "F.Mask" "F.Paste")
			(net "HSC_SCREF")
		)
		(pad "2" smd circle
			(at 0.40005 0)
			(size 0 0)
			(layers "F.Cu" "F.Mask" "F.Paste")
			(net "HSC_SCREF_4")
		)
	)
	(footprint ""
		(layer "F.Cu")
		(at 366.534446 -30.084522 -90)
		(property "Reference" "R818"
			(at 0 0 270)
			(layer "F.SilkS")
			(hide yes)
			(effects
				(font
					(size 1.27 1.27)
				)
			)
		)
		(property "Value" ""
			(at 0 0 270)
			(layer "F.Fab")
			(effects
				(font
					(size 1.27 1.27)
				)
			)
		)
		(duplicate_pad_numbers_are_jumpers no)
		(fp_line
			(start -0.7874 0.4064)
			(end -0.7874 -0.4064)
			(stroke
				(width 0.1524)
				(type default)
			)
			(layer "F.SilkS")
		)
		(fp_line
			(start 0.7874 0.4064)
			(end -0.7874 0.4064)
			(stroke
				(width 0.1524)
				(type default)
			)
			(layer "F.SilkS")
		)
		(fp_line
			(start -0.7874 -0.4064)
			(end 0.7874 -0.4064)
			(stroke
				(width 0.1524)
				(type default)
			)
			(layer "F.SilkS")
		)
		(fp_line
			(start 0.7874 -0.4064)
			(end 0.7874 0.4064)
			(stroke
				(width 0.1524)
				(type default)
			)
			(layer "F.SilkS")
		)
		(fp_line
			(start -0.67945 0.3048)
			(end -0.67945 -0.305054)
			(stroke
				(width 0.1)
				(type default)
			)
			(layer "F.Fab")
		)
		(fp_line
			(start -0.12065 0.3048)
			(end -0.67945 0.3048)
			(stroke
				(width 0.1)
				(type default)
			)
			(layer "F.Fab")
		)
		(fp_line
			(start 0.120396 0.3048)
			(end 0.120396 0.2794)
			(stroke
				(width 0.1)
				(type default)
			)
			(layer "F.Fab")
		)
		(fp_line
			(start 0.67945 0.3048)
			(end 0.120396 0.3048)
			(stroke
				(width 0.1)
				(type default)
			)
			(layer "F.Fab")
		)
		(fp_line
			(start -0.12065 0.2794)
			(end -0.12065 0.3048)
			(stroke
				(width 0.1)
				(type default)
			)
			(layer "F.Fab")
		)
		(fp_line
			(start 0.120396 0.2794)
			(end -0.12065 0.2794)
			(stroke
				(width 0.1)
				(type default)
			)
			(layer "F.Fab")
		)
		(fp_line
			(start -0.12065 -0.2794)
			(end 0.12065 -0.2794)
			(stroke
				(width 0.1)
				(type default)
			)
			(layer "F.Fab")
		)
		(fp_line
			(start 0.12065 -0.2794)
			(end 0.12065 -0.3048)
			(stroke
				(width 0.1)
				(type default)
			)
			(layer "F.Fab")
		)
		(fp_line
			(start 0.12065 -0.3048)
			(end 0.67945 -0.3048)
			(stroke
				(width 0.1)
				(type default)
			)
			(layer "F.Fab")
		)
		(fp_line
			(start 0.67945 -0.3048)
			(end 0.67945 0.3048)
			(stroke
				(width 0.1)
				(type default)
			)
			(layer "F.Fab")
		)
		(fp_line
			(start -0.67945 -0.305054)
			(end -0.12065 -0.305054)
			(stroke
				(width 0.1)
				(type default)
			)
			(layer "F.Fab")
		)
		(fp_line
			(start -0.12065 -0.305054)
			(end -0.12065 -0.2794)
			(stroke
				(width 0.1)
				(type default)
			)
			(layer "F.Fab")
		)
		(pad "1" smd circle
			(at -0.40005 0 270)
			(size 0 0)
			(layers "F.Cu" "F.Mask" "F.Paste")
			(net "UART_CPU0_LVC3_UART0_R_TX")
		)
		(pad "2" smd circle
			(at 0.40005 0 270)
			(size 0 0)
			(layers "F.Cu" "F.Mask" "F.Paste")
			(net "UART_CPU0_LVC3_UART0_TX")
		)
	)
	(footprint ""
		(layer "F.Cu")
		(at 366.36579 -392.1252)
		(property "Reference" "R1120"
			(at 0 0 0)
			(layer "F.SilkS")
			(hide yes)
			(effects
				(font
					(size 1.27 1.27)
				)
			)
		)
		(property "Value" ""
			(at 0 0 0)
			(layer "F.Fab")
			(effects
				(font
					(size 1.27 1.27)
				)
			)
		)
		(duplicate_pad_numbers_are_jumpers no)
		(fp_line
			(start -0.32512 -0.175006)
			(end 0.32512 -0.175006)
			(stroke
				(width 0.1)
				(type default)
			)
			(layer "F.Fab")
		)
		(fp_line
			(start -0.32512 0.175006)
			(end -0.32512 -0.175006)
			(stroke
				(width 0.1)
				(type default)
			)
			(layer "F.Fab")
		)
		(fp_line
			(start 0.32512 -0.175006)
			(end 0.32512 0.175006)
			(stroke
				(width 0.1)
				(type default)
			)
			(layer "F.Fab")
		)
		(fp_line
			(start 0.32512 0.175006)
			(end -0.32512 0.175006)
			(stroke
				(width 0.1)
				(type default)
			)
			(layer "F.Fab")
		)
		(pad "1" smd rect
			(at -0.2667 0)
			(size 0.3048 0.381)
			(layers "F.Cu" "F.Mask" "F.Paste")
			(net "TEST2_RT_CPU0_P3")
		)
		(pad "2" smd rect
			(at 0.2667 0 180)
			(size 0.3048 0.381)
			(layers "F.Cu" "F.Mask" "F.Paste")
			(net "GND")
		)
	)
	(footprint ""
		(layer "F.Cu")
		(at 410.846524 -143.872204 90)
		(property "Reference" "PC1847"
			(at 0 0 90)
			(layer "F.SilkS")
			(hide yes)
			(effects
				(font
					(size 1.27 1.27)
				)
			)
		)
		(property "Value" ""
			(at 0 0 90)
			(layer "F.Fab")
			(effects
				(font
					(size 1.27 1.27)
				)
			)
		)
		(duplicate_pad_numbers_are_jumpers no)
		(fp_line
			(start 0.7874 -0.4064)
			(end 0.7874 0.4064)
			(stroke
				(width 0.1524)
				(type default)
			)
			(layer "F.SilkS")
		)
		(fp_line
			(start -0.7874 -0.4064)
			(end 0.7874 -0.4064)
			(stroke
				(width 0.1524)
				(type default)
			)
			(layer "F.SilkS")
		)
		(fp_line
			(start 0.7874 0.4064)
			(end -0.7874 0.4064)
			(stroke
				(width 0.1524)
				(type default)
			)
			(layer "F.SilkS")
		)
		(fp_line
			(start -0.7874 0.4064)
			(end -0.7874 -0.4064)
			(stroke
				(width 0.1524)
				(type default)
			)
			(layer "F.SilkS")
		)
		(fp_line
			(start -0.12065 -0.305054)
			(end -0.12065 -0.2794)
			(stroke
				(width 0.1)
				(type default)
			)
			(layer "F.Fab")
		)
		(fp_line
			(start -0.67945 -0.305054)
			(end -0.12065 -0.305054)
			(stroke
				(width 0.1)
				(type default)
			)
			(layer "F.Fab")
		)
		(fp_line
			(start 0.67945 -0.3048)
			(end 0.67945 0.3048)
			(stroke
				(width 0.1)
				(type default)
			)
			(layer "F.Fab")
		)
		(fp_line
			(start 0.12065 -0.3048)
			(end 0.67945 -0.3048)
			(stroke
				(width 0.1)
				(type default)
			)
			(layer "F.Fab")
		)
		(fp_line
			(start 0.12065 -0.2794)
			(end 0.12065 -0.3048)
			(stroke
				(width 0.1)
				(type default)
			)
			(layer "F.Fab")
		)
		(fp_line
			(start -0.12065 -0.2794)
			(end 0.12065 -0.2794)
			(stroke
				(width 0.1)
				(type default)
			)
			(layer "F.Fab")
		)
		(fp_line
			(start 0.120396 0.2794)
			(end -0.12065 0.2794)
			(stroke
				(width 0.1)
				(type default)
			)
			(layer "F.Fab")
		)
		(fp_line
			(start -0.12065 0.2794)
			(end -0.12065 0.3048)
			(stroke
				(width 0.1)
				(type default)
			)
			(layer "F.Fab")
		)
		(fp_line
			(start 0.67945 0.3048)
			(end 0.120396 0.3048)
			(stroke
				(width 0.1)
				(type default)
			)
			(layer "F.Fab")
		)
		(fp_line
			(start 0.120396 0.3048)
			(end 0.120396 0.2794)
			(stroke
				(width 0.1)
				(type default)
			)
			(layer "F.Fab")
		)
		(fp_line
			(start -0.12065 0.3048)
			(end -0.67945 0.3048)
			(stroke
				(width 0.1)
				(type default)
			)
			(layer "F.Fab")
		)
		(fp_line
			(start -0.67945 0.3048)
			(end -0.67945 -0.305054)
			(stroke
				(width 0.1)
				(type default)
			)
			(layer "F.Fab")
		)
		(pad "1" smd circle
			(at -0.40005 0 90)
			(size 0 0)
			(layers "F.Cu" "F.Mask" "F.Paste")
			(net "SW_P5V_AUX_BST")
		)
		(pad "2" smd circle
			(at 0.40005 0 90)
			(size 0 0)
			(layers "F.Cu" "F.Mask" "F.Paste")
			(net "SW_P5V_AUX_SW")
		)
	)
	(footprint ""
		(layer "F.Cu")
		(at 461.342232 -51.696366 -90)
		(property "Reference" "PR8389"
			(at 0 0 270)
			(layer "F.SilkS")
			(hide yes)
			(effects
				(font
					(size 1.27 1.27)
				)
			)
		)
		(property "Value" ""
			(at 0 0 270)
			(layer "F.Fab")
			(effects
				(font
					(size 1.27 1.27)
				)
			)
		)
		(duplicate_pad_numbers_are_jumpers no)
		(fp_line
			(start -0.7874 0.4064)
			(end -0.7874 -0.4064)
			(stroke
				(width 0.1524)
				(type default)
			)
			(layer "F.SilkS")
		)
		(fp_line
			(start 0.7874 0.4064)
			(end -0.7874 0.4064)
			(stroke
				(width 0.1524)
				(type default)
			)
			(layer "F.SilkS")
		)
		(fp_line
			(start -0.7874 -0.4064)
			(end 0.7874 -0.4064)
			(stroke
				(width 0.1524)
				(type default)
			)
			(layer "F.SilkS")
		)
		(fp_line
			(start 0.7874 -0.4064)
			(end 0.7874 0.4064)
			(stroke
				(width 0.1524)
				(type default)
			)
			(layer "F.SilkS")
		)
		(fp_line
			(start -0.67945 0.3048)
			(end -0.67945 -0.305054)
			(stroke
				(width 0.1)
				(type default)
			)
			(layer "F.Fab")
		)
		(fp_line
			(start -0.12065 0.3048)
			(end -0.67945 0.3048)
			(stroke
				(width 0.1)
				(type default)
			)
			(layer "F.Fab")
		)
		(fp_line
			(start 0.120396 0.3048)
			(end 0.120396 0.2794)
			(stroke
				(width 0.1)
				(type default)
			)
			(layer "F.Fab")
		)
		(fp_line
			(start 0.67945 0.3048)
			(end 0.120396 0.3048)
			(stroke
				(width 0.1)
				(type default)
			)
			(layer "F.Fab")
		)
		(fp_line
			(start -0.12065 0.2794)
			(end -0.12065 0.3048)
			(stroke
				(width 0.1)
				(type default)
			)
			(layer "F.Fab")
		)
		(fp_line
			(start 0.120396 0.2794)
			(end -0.12065 0.2794)
			(stroke
				(width 0.1)
				(type default)
			)
			(layer "F.Fab")
		)
		(fp_line
			(start -0.12065 -0.2794)
			(end 0.12065 -0.2794)
			(stroke
				(width 0.1)
				(type default)
			)
			(layer "F.Fab")
		)
		(fp_line
			(start 0.12065 -0.2794)
			(end 0.12065 -0.3048)
			(stroke
				(width 0.1)
				(type default)
			)
			(layer "F.Fab")
		)
		(fp_line
			(start 0.12065 -0.3048)
			(end 0.67945 -0.3048)
			(stroke
				(width 0.1)
				(type default)
			)
			(layer "F.Fab")
		)
		(fp_line
			(start 0.67945 -0.3048)
			(end 0.67945 0.3048)
			(stroke
				(width 0.1)
				(type default)
			)
			(layer "F.Fab")
		)
		(fp_line
			(start -0.67945 -0.305054)
			(end -0.12065 -0.305054)
			(stroke
				(width 0.1)
				(type default)
			)
			(layer "F.Fab")
		)
		(fp_line
			(start -0.12065 -0.305054)
			(end -0.12065 -0.2794)
			(stroke
				(width 0.1)
				(type default)
			)
			(layer "F.Fab")
		)
		(pad "1" smd circle
			(at -0.40005 0 270)
			(size 0 0)
			(layers "F.Cu" "F.Mask" "F.Paste")
			(net "P3V3_AUX_VDRV")
		)
		(pad "2" smd circle
			(at 0.40005 0 270)
			(size 0 0)
			(layers "F.Cu" "F.Mask" "F.Paste")
			(net "P3V3_AUX_VCC")
		)
	)
)
